(kicad_pcb
	(version 20260206)
	(generator "pcbnew")
	(generator_version "10.0")
	(general
		(thickness 1.6)
		(legacy_teardrops no)
	)
	(paper "A4")
	(title_block
		(title "Wiwynn_Tioga_Pass_MB.brd")
		(comment 1 "Tioga Pass / footprint 3319 of 4770 (J6L2), pads 124-243 of 291")
	)
	(layers
		(0 "F.Cu" signal "TOP")
		(4 "In1.Cu" signal "L2GND")
		(6 "In2.Cu" signal "L3")
		(8 "In3.Cu" signal "L4GND")
		(10 "In4.Cu" signal "L5")
		(12 "In5.Cu" signal "L6GND")
		(14 "In6.Cu" signal "L7VCC")
		(16 "In7.Cu" signal "L8VCC")
		(18 "In8.Cu" signal "L9GND")
		(20 "In9.Cu" signal "L10")
		(22 "In10.Cu" signal "L11GND")
		(24 "In11.Cu" signal "L12")
		(26 "In12.Cu" signal "L13GND")
		(2 "B.Cu" signal "BOTTOM")
		(9 "F.Adhes" user "F.Adhesive")
		(11 "B.Adhes" user "B.Adhesive")
		(13 "F.Paste" user "Package Geometry/Pastemask Top")
		(15 "B.Paste" user "Package Geometry/Pastemask Bottom")
		(5 "F.SilkS" user "Ref Des/Silkscreen Top")
		(7 "B.SilkS" user "Ref Des/Silkscreen Bottom")
		(1 "F.Mask" user "Board Geometry/Soldermask Top")
		(3 "B.Mask" user "Board Geometry/Soldermask Bottom")
		(17 "Dwgs.User" user "User.Drawings")
		(19 "Cmts.User" user "User.Comments")
		(21 "Eco1.User" user "User.Eco1")
		(23 "Eco2.User" user "User.Eco2")
		(25 "Edge.Cuts" user "Board Geometry/Outline")
		(27 "Margin" user)
		(31 "F.CrtYd" user "Package Geometry/Place Bound Top")
		(29 "B.CrtYd" user "Package Geometry/Place Bound Bottom")
		(35 "F.Fab" user "Ref Des/Assembly Top")
		(33 "B.Fab" user "Ref Des/Assembly Bottom")
	)
	(footprint ""
		(layer "B.Cu")
		(at 194.700398 -142.477236 90)
		(property "Reference" "J6L2"
			(at 2.276348 38.21811 0)
			(unlocked yes)
			(layer "B.SilkS")
			(effects
				(font
					(size 0.7874 0.5842)
					(thickness 0.1524)
				)
				(justify left mirror)
			)
		)
		(property "Value" ""
			(at 0 0 90)
			(layer "B.Fab")
			(effects
				(font
					(size 1.27 1.27)
				)
				(justify mirror)
			)
		)
		(duplicate_pad_numbers_are_jumpers no)
		(pad "121" smd rect
			(at 0 107.100116 270)
			(size 1.8034 0.508)
			(layers "B.Cu" "B.Mask" "B.Paste")
			(net "M_E_DQS_DP<15>")
		)
		(pad "122" smd rect
			(at 0 107.95 270)
			(size 1.8034 0.508)
			(layers "B.Cu" "B.Mask" "B.Paste")
			(net "M_E_DQS_DN<15>")
		)
		(pad "123" smd rect
			(at 0 108.799884 270)
			(size 1.8034 0.508)
			(layers "B.Cu" "B.Mask" "B.Paste")
			(net "GND")
		)
		(pad "124" smd rect
			(at 0 109.650022 270)
			(size 1.8034 0.508)
			(layers "B.Cu" "B.Mask" "B.Paste")
			(net "M_E_DQ<54>")
		)
		(pad "125" smd rect
			(at 0 110.499906 270)
			(size 1.8034 0.508)
			(layers "B.Cu" "B.Mask" "B.Paste")
			(net "GND")
		)
		(pad "126" smd rect
			(at 0 111.350044 270)
			(size 1.8034 0.508)
			(layers "B.Cu" "B.Mask" "B.Paste")
			(net "M_E_DQ<50>")
		)
		(pad "127" smd rect
			(at 0 112.199928 270)
			(size 1.8034 0.508)
			(layers "B.Cu" "B.Mask" "B.Paste")
			(net "GND")
		)
		(pad "128" smd rect
			(at 0 113.050066 270)
			(size 1.8034 0.508)
			(layers "B.Cu" "B.Mask" "B.Paste")
			(net "M_E_DQ<60>")
		)
		(pad "129" smd rect
			(at 0 113.89995 270)
			(size 1.8034 0.508)
			(layers "B.Cu" "B.Mask" "B.Paste")
			(net "GND")
		)
		(pad "130" smd rect
			(at 0 114.750088 270)
			(size 1.8034 0.508)
			(layers "B.Cu" "B.Mask" "B.Paste")
			(net "M_E_DQ<56>")
		)
		(pad "131" smd rect
			(at 0 115.599972 270)
			(size 1.8034 0.508)
			(layers "B.Cu" "B.Mask" "B.Paste")
			(net "GND")
		)
		(pad "132" smd rect
			(at 0 116.45011 270)
			(size 1.8034 0.508)
			(layers "B.Cu" "B.Mask" "B.Paste")
			(net "M_E_DQS_DP<16>")
		)
		(pad "133" smd rect
			(at 0 117.299994 270)
			(size 1.8034 0.508)
			(layers "B.Cu" "B.Mask" "B.Paste")
			(net "M_E_DQS_DN<16>")
		)
		(pad "134" smd rect
			(at 0 118.149878 270)
			(size 1.8034 0.508)
			(layers "B.Cu" "B.Mask" "B.Paste")
			(net "GND")
		)
		(pad "135" smd rect
			(at 0 119.000016 270)
			(size 1.8034 0.508)
			(layers "B.Cu" "B.Mask" "B.Paste")
			(net "M_E_DQ<62>")
		)
		(pad "136" smd rect
			(at 0 119.8499 270)
			(size 1.8034 0.508)
			(layers "B.Cu" "B.Mask" "B.Paste")
			(net "GND")
		)
		(pad "137" smd rect
			(at 0 120.700038 270)
			(size 1.8034 0.508)
			(layers "B.Cu" "B.Mask" "B.Paste")
			(net "M_E_DQ<58>")
		)
		(pad "138" smd rect
			(at 0 121.549922 270)
			(size 1.8034 0.508)
			(layers "B.Cu" "B.Mask" "B.Paste")
			(net "GND")
		)
		(pad "139" smd rect
			(at 0 122.40006 270)
			(size 1.8034 0.508)
			(layers "B.Cu" "B.Mask" "B.Paste")
			(net "PVPP_DEF")
		)
		(pad "140" smd rect
			(at 0 123.249944 270)
			(size 1.8034 0.508)
			(layers "B.Cu" "B.Mask" "B.Paste")
			(net "PVPP_DEF")
		)
		(pad "141" smd rect
			(at 0 124.100082 270)
			(size 1.8034 0.508)
			(layers "B.Cu" "B.Mask" "B.Paste")
			(net "SMB_DDR_DEF_VPP_SCL")
		)
		(pad "142" smd rect
			(at 0 124.949966 270)
			(size 1.8034 0.508)
			(layers "B.Cu" "B.Mask" "B.Paste")
			(net "PVPP_DEF")
		)
		(pad "143" smd rect
			(at 0 125.800104 270)
			(size 1.8034 0.508)
			(layers "B.Cu" "B.Mask" "B.Paste")
			(net "PVPP_DEF")
		)
		(pad "144" smd rect
			(at 0 126.649988 270)
			(size 1.8034 0.508)
			(layers "B.Cu" "B.Mask" "B.Paste")
			(net "TP_CH_E_DIMM_E1_RFU_2")
		)
		(pad "145" smd rect
			(at -4.59994 0 270)
			(size 1.8034 0.508)
			(layers "B.Cu" "B.Mask" "B.Paste")
			(net "P12V_NVDIMM_DEF")
		)
		(pad "146" smd rect
			(at -4.59994 0.849884 270)
			(size 1.8034 0.508)
			(layers "B.Cu" "B.Mask" "B.Paste")
			(net "M_E_VREF")
		)
		(pad "147" smd rect
			(at -4.59994 1.700022 270)
			(size 1.8034 0.508)
			(layers "B.Cu" "B.Mask" "B.Paste")
			(net "GND")
		)
		(pad "148" smd rect
			(at -4.59994 2.549906 270)
			(size 1.8034 0.508)
			(layers "B.Cu" "B.Mask" "B.Paste")
			(net "M_E_DQ<5>")
		)
		(pad "149" smd rect
			(at -4.59994 3.400044 270)
			(size 1.8034 0.508)
			(layers "B.Cu" "B.Mask" "B.Paste")
			(net "GND")
		)
		(pad "150" smd rect
			(at -4.59994 4.249928 270)
			(size 1.8034 0.508)
			(layers "B.Cu" "B.Mask" "B.Paste")
			(net "M_E_DQ<1>")
		)
		(pad "151" smd rect
			(at -4.59994 5.100066 270)
			(size 1.8034 0.508)
			(layers "B.Cu" "B.Mask" "B.Paste")
			(net "GND")
		)
		(pad "152" smd rect
			(at -4.59994 5.94995 270)
			(size 1.8034 0.508)
			(layers "B.Cu" "B.Mask" "B.Paste")
			(net "M_E_DQS_DN<0>")
		)
		(pad "153" smd rect
			(at -4.59994 6.800088 270)
			(size 1.8034 0.508)
			(layers "B.Cu" "B.Mask" "B.Paste")
			(net "M_E_DQS_DP<0>")
		)
		(pad "154" smd rect
			(at -4.59994 7.649972 270)
			(size 1.8034 0.508)
			(layers "B.Cu" "B.Mask" "B.Paste")
			(net "GND")
		)
		(pad "155" smd rect
			(at -4.59994 8.50011 270)
			(size 1.8034 0.508)
			(layers "B.Cu" "B.Mask" "B.Paste")
			(net "M_E_DQ<7>")
		)
		(pad "156" smd rect
			(at -4.59994 9.349994 270)
			(size 1.8034 0.508)
			(layers "B.Cu" "B.Mask" "B.Paste")
			(net "GND")
		)
		(pad "157" smd rect
			(at -4.59994 10.199878 270)
			(size 1.8034 0.508)
			(layers "B.Cu" "B.Mask" "B.Paste")
			(net "M_E_DQ<3>")
		)
		(pad "158" smd rect
			(at -4.59994 11.050016 270)
			(size 1.8034 0.508)
			(layers "B.Cu" "B.Mask" "B.Paste")
			(net "GND")
		)
		(pad "159" smd rect
			(at -4.59994 11.8999 270)
			(size 1.8034 0.508)
			(layers "B.Cu" "B.Mask" "B.Paste")
			(net "M_E_DQ<13>")
		)
		(pad "160" smd rect
			(at -4.59994 12.750038 270)
			(size 1.8034 0.508)
			(layers "B.Cu" "B.Mask" "B.Paste")
			(net "GND")
		)
		(pad "161" smd rect
			(at -4.59994 13.599922 270)
			(size 1.8034 0.508)
			(layers "B.Cu" "B.Mask" "B.Paste")
			(net "M_E_DQ<9>")
		)
		(pad "162" smd rect
			(at -4.59994 14.45006 270)
			(size 1.8034 0.508)
			(layers "B.Cu" "B.Mask" "B.Paste")
			(net "GND")
		)
		(pad "163" smd rect
			(at -4.59994 15.299944 270)
			(size 1.8034 0.508)
			(layers "B.Cu" "B.Mask" "B.Paste")
			(net "M_E_DQS_DN<1>")
		)
		(pad "164" smd rect
			(at -4.59994 16.150082 270)
			(size 1.8034 0.508)
			(layers "B.Cu" "B.Mask" "B.Paste")
			(net "M_E_DQS_DP<1>")
		)
		(pad "165" smd rect
			(at -4.59994 16.999966 270)
			(size 1.8034 0.508)
			(layers "B.Cu" "B.Mask" "B.Paste")
			(net "GND")
		)
		(pad "166" smd rect
			(at -4.59994 17.850104 270)
			(size 1.8034 0.508)
			(layers "B.Cu" "B.Mask" "B.Paste")
			(net "M_E_DQ<15>")
		)
		(pad "167" smd rect
			(at -4.59994 18.699988 270)
			(size 1.8034 0.508)
			(layers "B.Cu" "B.Mask" "B.Paste")
			(net "GND")
		)
		(pad "168" smd rect
			(at -4.59994 19.550126 270)
			(size 1.8034 0.508)
			(layers "B.Cu" "B.Mask" "B.Paste")
			(net "M_E_DQ<11>")
		)
		(pad "169" smd rect
			(at -4.59994 20.40001 270)
			(size 1.8034 0.508)
			(layers "B.Cu" "B.Mask" "B.Paste")
			(net "GND")
		)
		(pad "170" smd rect
			(at -4.59994 21.249894 270)
			(size 1.8034 0.508)
			(layers "B.Cu" "B.Mask" "B.Paste")
			(net "M_E_DQ<21>")
		)
		(pad "171" smd rect
			(at -4.59994 22.100032 270)
			(size 1.8034 0.508)
			(layers "B.Cu" "B.Mask" "B.Paste")
			(net "GND")
		)
		(pad "172" smd rect
			(at -4.59994 22.949916 270)
			(size 1.8034 0.508)
			(layers "B.Cu" "B.Mask" "B.Paste")
			(net "M_E_DQ<17>")
		)
		(pad "173" smd rect
			(at -4.59994 23.800054 270)
			(size 1.8034 0.508)
			(layers "B.Cu" "B.Mask" "B.Paste")
			(net "GND")
		)
		(pad "174" smd rect
			(at -4.59994 24.649938 270)
			(size 1.8034 0.508)
			(layers "B.Cu" "B.Mask" "B.Paste")
			(net "M_E_DQS_DN<2>")
		)
		(pad "175" smd rect
			(at -4.59994 25.500076 270)
			(size 1.8034 0.508)
			(layers "B.Cu" "B.Mask" "B.Paste")
			(net "M_E_DQS_DP<2>")
		)
		(pad "176" smd rect
			(at -4.59994 26.34996 270)
			(size 1.8034 0.508)
			(layers "B.Cu" "B.Mask" "B.Paste")
			(net "GND")
		)
		(pad "177" smd rect
			(at -4.59994 27.200098 270)
			(size 1.8034 0.508)
			(layers "B.Cu" "B.Mask" "B.Paste")
			(net "M_E_DQ<23>")
		)
		(pad "178" smd rect
			(at -4.59994 28.049982 270)
			(size 1.8034 0.508)
			(layers "B.Cu" "B.Mask" "B.Paste")
			(net "GND")
		)
		(pad "179" smd rect
			(at -4.59994 28.90012 270)
			(size 1.8034 0.508)
			(layers "B.Cu" "B.Mask" "B.Paste")
			(net "M_E_DQ<19>")
		)
		(pad "180" smd rect
			(at -4.59994 29.750004 270)
			(size 1.8034 0.508)
			(layers "B.Cu" "B.Mask" "B.Paste")
			(net "GND")
		)
		(pad "181" smd rect
			(at -4.59994 30.599888 270)
			(size 1.8034 0.508)
			(layers "B.Cu" "B.Mask" "B.Paste")
			(net "M_E_DQ<29>")
		)
		(pad "182" smd rect
			(at -4.59994 31.450026 270)
			(size 1.8034 0.508)
			(layers "B.Cu" "B.Mask" "B.Paste")
			(net "GND")
		)
		(pad "183" smd rect
			(at -4.59994 32.29991 270)
			(size 1.8034 0.508)
			(layers "B.Cu" "B.Mask" "B.Paste")
			(net "M_E_DQ<25>")
		)
		(pad "184" smd rect
			(at -4.59994 33.150048 270)
			(size 1.8034 0.508)
			(layers "B.Cu" "B.Mask" "B.Paste")
			(net "GND")
		)
		(pad "185" smd rect
			(at -4.59994 33.999932 270)
			(size 1.8034 0.508)
			(layers "B.Cu" "B.Mask" "B.Paste")
			(net "M_E_DQS_DN<3>")
		)
		(pad "186" smd rect
			(at -4.59994 34.85007 270)
			(size 1.8034 0.508)
			(layers "B.Cu" "B.Mask" "B.Paste")
			(net "M_E_DQS_DP<3>")
		)
		(pad "187" smd rect
			(at -4.59994 35.699954 270)
			(size 1.8034 0.508)
			(layers "B.Cu" "B.Mask" "B.Paste")
			(net "GND")
		)
		(pad "188" smd rect
			(at -4.59994 36.550092 270)
			(size 1.8034 0.508)
			(layers "B.Cu" "B.Mask" "B.Paste")
			(net "M_E_DQ<31>")
		)
		(pad "189" smd rect
			(at -4.59994 37.399976 270)
			(size 1.8034 0.508)
			(layers "B.Cu" "B.Mask" "B.Paste")
			(net "GND")
		)
		(pad "190" smd rect
			(at -4.59994 38.250114 270)
			(size 1.8034 0.508)
			(layers "B.Cu" "B.Mask" "B.Paste")
			(net "M_E_DQ<27>")
		)
		(pad "191" smd rect
			(at -4.59994 39.099998 270)
			(size 1.8034 0.508)
			(layers "B.Cu" "B.Mask" "B.Paste")
			(net "GND")
		)
		(pad "192" smd rect
			(at -4.59994 39.949882 270)
			(size 1.8034 0.508)
			(layers "B.Cu" "B.Mask" "B.Paste")
			(net "M_E_ECC<5>")
		)
		(pad "193" smd rect
			(at -4.59994 40.80002 270)
			(size 1.8034 0.508)
			(layers "B.Cu" "B.Mask" "B.Paste")
			(net "GND")
		)
		(pad "194" smd rect
			(at -4.59994 41.649904 270)
			(size 1.8034 0.508)
			(layers "B.Cu" "B.Mask" "B.Paste")
			(net "M_E_ECC<1>")
		)
		(pad "195" smd rect
			(at -4.59994 42.500042 270)
			(size 1.8034 0.508)
			(layers "B.Cu" "B.Mask" "B.Paste")
			(net "GND")
		)
		(pad "196" smd rect
			(at -4.59994 43.349926 270)
			(size 1.8034 0.508)
			(layers "B.Cu" "B.Mask" "B.Paste")
			(net "M_E_DQS_DN<8>")
		)
		(pad "197" smd rect
			(at -4.59994 44.200064 270)
			(size 1.8034 0.508)
			(layers "B.Cu" "B.Mask" "B.Paste")
			(net "M_E_DQS_DP<8>")
		)
		(pad "198" smd rect
			(at -4.59994 45.049948 270)
			(size 1.8034 0.508)
			(layers "B.Cu" "B.Mask" "B.Paste")
			(net "GND")
		)
		(pad "199" smd rect
			(at -4.59994 45.900086 270)
			(size 1.8034 0.508)
			(layers "B.Cu" "B.Mask" "B.Paste")
			(net "M_E_ECC<7>")
		)
		(pad "200" smd rect
			(at -4.59994 46.74997 270)
			(size 1.8034 0.508)
			(layers "B.Cu" "B.Mask" "B.Paste")
			(net "GND")
		)
		(pad "201" smd rect
			(at -4.59994 47.600108 270)
			(size 1.8034 0.508)
			(layers "B.Cu" "B.Mask" "B.Paste")
			(net "M_E_ECC<3>")
		)
		(pad "202" smd rect
			(at -4.59994 48.449992 270)
			(size 1.8034 0.508)
			(layers "B.Cu" "B.Mask" "B.Paste")
			(net "GND")
		)
		(pad "203" smd rect
			(at -4.59994 49.299876 270)
			(size 1.8034 0.508)
			(layers "B.Cu" "B.Mask" "B.Paste")
			(net "M_E_CKE<3>")
		)
		(pad "204" smd rect
			(at -4.59994 50.150014 270)
			(size 1.8034 0.508)
			(layers "B.Cu" "B.Mask" "B.Paste")
			(net "PVDDQ_DEF")
		)
		(pad "205" smd rect
			(at -4.59994 50.999898 270)
			(size 1.8034 0.508)
			(layers "B.Cu" "B.Mask" "B.Paste")
			(net "TP_CH_E_DIMM_E1_RFU_0")
		)
		(pad "206" smd rect
			(at -4.59994 51.850036 270)
			(size 1.8034 0.508)
			(layers "B.Cu" "B.Mask" "B.Paste")
			(net "PVDDQ_DEF")
		)
		(pad "207" smd rect
			(at -4.59994 52.69992 270)
			(size 1.8034 0.508)
			(layers "B.Cu" "B.Mask" "B.Paste")
			(net "M_E_BG<1>")
		)
		(pad "208" smd rect
			(at -4.59994 53.550058 270)
			(size 1.8034 0.508)
			(layers "B.Cu" "B.Mask" "B.Paste")
			(net "M_E_ALERT_N")
		)
		(pad "209" smd rect
			(at -4.59994 54.399942 270)
			(size 1.8034 0.508)
			(layers "B.Cu" "B.Mask" "B.Paste")
			(net "PVDDQ_DEF")
		)
		(pad "210" smd rect
			(at -4.59994 55.25008 270)
			(size 1.8034 0.508)
			(layers "B.Cu" "B.Mask" "B.Paste")
			(net "M_E_MA<11>")
		)
		(pad "211" smd rect
			(at -4.59994 56.099964 270)
			(size 1.8034 0.508)
			(layers "B.Cu" "B.Mask" "B.Paste")
			(net "M_E_MA<7>")
		)
		(pad "212" smd rect
			(at -4.59994 56.950102 270)
			(size 1.8034 0.508)
			(layers "B.Cu" "B.Mask" "B.Paste")
			(net "PVDDQ_DEF")
		)
		(pad "213" smd rect
			(at -4.59994 57.799986 270)
			(size 1.8034 0.508)
			(layers "B.Cu" "B.Mask" "B.Paste")
			(net "M_E_MA<5>")
		)
		(pad "214" smd rect
			(at -4.59994 58.650124 270)
			(size 1.8034 0.508)
			(layers "B.Cu" "B.Mask" "B.Paste")
			(net "M_E_MA<4>")
		)
		(pad "215" smd rect
			(at -4.59994 59.500008 270)
			(size 1.8034 0.508)
			(layers "B.Cu" "B.Mask" "B.Paste")
			(net "PVDDQ_DEF")
		)
		(pad "216" smd rect
			(at -4.59994 60.349892 270)
			(size 1.8034 0.508)
			(layers "B.Cu" "B.Mask" "B.Paste")
			(net "M_E_MA<2>")
		)
		(pad "217" smd rect
			(at -4.59994 61.20003 270)
			(size 1.8034 0.508)
			(layers "B.Cu" "B.Mask" "B.Paste")
			(net "PVDDQ_DEF")
		)
		(pad "218" smd rect
			(at -4.59994 62.049914 270)
			(size 1.8034 0.508)
			(layers "B.Cu" "B.Mask" "B.Paste")
			(net "M_E_CLK_DP<3>")
		)
		(pad "219" smd rect
			(at -4.59994 62.900052 270)
			(size 1.8034 0.508)
			(layers "B.Cu" "B.Mask" "B.Paste")
			(net "M_E_CLK_DN<3>")
		)
		(pad "220" smd rect
			(at -4.59994 63.749936 270)
			(size 1.8034 0.508)
			(layers "B.Cu" "B.Mask" "B.Paste")
			(net "PVDDQ_DEF")
		)
		(pad "221" smd rect
			(at -4.59994 64.600074 270)
			(size 1.8034 0.508)
			(layers "B.Cu" "B.Mask" "B.Paste")
			(net "PVTT_DEF")
		)
		(pad "222" smd rect
			(at -4.59994 70.550024 270)
			(size 1.8034 0.508)
			(layers "B.Cu" "B.Mask" "B.Paste")
			(net "M_E_PAR")
		)
		(pad "223" smd rect
			(at -4.59994 71.399908 270)
			(size 1.8034 0.508)
			(layers "B.Cu" "B.Mask" "B.Paste")
			(net "PVDDQ_DEF")
		)
		(pad "224" smd rect
			(at -4.59994 72.250046 270)
			(size 1.8034 0.508)
			(layers "B.Cu" "B.Mask" "B.Paste")
			(net "M_E_BA<1>")
		)
		(pad "225" smd rect
			(at -4.59994 73.09993 270)
			(size 1.8034 0.508)
			(layers "B.Cu" "B.Mask" "B.Paste")
			(net "M_E_MA<10>")
		)
		(pad "226" smd rect
			(at -4.59994 73.950068 270)
			(size 1.8034 0.508)
			(layers "B.Cu" "B.Mask" "B.Paste")
			(net "PVDDQ_DEF")
		)
		(pad "227" smd rect
			(at -4.59994 74.799952 270)
			(size 1.8034 0.508)
			(layers "B.Cu" "B.Mask" "B.Paste")
			(net "TP_CH_E_DIMM_E1_RFU_1")
		)
		(pad "228" smd rect
			(at -4.59994 75.65009 270)
			(size 1.8034 0.508)
			(layers "B.Cu" "B.Mask" "B.Paste")
			(net "M_E_MA<14>")
		)
		(pad "229" smd rect
			(at -4.59994 76.499974 270)
			(size 1.8034 0.508)
			(layers "B.Cu" "B.Mask" "B.Paste")
			(net "PVDDQ_DEF")
		)
		(pad "230" smd rect
			(at -4.59994 77.350112 270)
			(size 1.8034 0.508)
			(layers "B.Cu" "B.Mask" "B.Paste")
			(net "FM_ADR_COMPLETE_DEF_N")
		)
		(pad "231" smd rect
			(at -4.59994 78.199996 270)
			(size 1.8034 0.508)
			(layers "B.Cu" "B.Mask" "B.Paste")
			(net "PVDDQ_DEF")
		)
		(pad "232" smd rect
			(at -4.59994 79.04988 270)
			(size 1.8034 0.508)
			(layers "B.Cu" "B.Mask" "B.Paste")
			(net "M_E_MA<13>")
		)
		(pad "233" smd rect
			(at -4.59994 79.900018 270)
			(size 1.8034 0.508)
			(layers "B.Cu" "B.Mask" "B.Paste")
			(net "PVDDQ_DEF")
		)
		(pad "234" smd rect
			(at -4.59994 80.749902 270)
			(size 1.8034 0.508)
			(layers "B.Cu" "B.Mask" "B.Paste")
			(net "M_E_MA<17>")
		)
		(pad "235" smd rect
			(at -4.59994 81.60004 270)
			(size 1.8034 0.508)
			(layers "B.Cu" "B.Mask" "B.Paste")
			(net "M_E_C<2>")
		)
		(pad "236" smd rect
			(at -4.59994 82.449924 270)
			(size 1.8034 0.508)
			(layers "B.Cu" "B.Mask" "B.Paste")
			(net "PVDDQ_DEF")
		)
		(pad "237" smd rect
			(at -4.59994 83.300062 270)
			(size 1.8034 0.508)
			(layers "B.Cu" "B.Mask" "B.Paste")
			(net "M_E_CS_N<7>")
		)
		(pad "238" smd rect
			(at -4.59994 84.149946 270)
			(size 1.8034 0.508)
			(layers "B.Cu" "B.Mask" "B.Paste")
			(net "GND")
		)
		(pad "239" smd rect
			(at -4.59994 85.000084 270)
			(size 1.8034 0.508)
			(layers "B.Cu" "B.Mask" "B.Paste")
			(net "GND")
		)
		(pad "240" smd rect
			(at -4.59994 85.849968 270)
			(size 1.8034 0.508)
			(layers "B.Cu" "B.Mask" "B.Paste")
			(net "M_E_DQ<37>")
		)
	)
)
